(kicad_pcb
	(version 20260206)
	(generator "pcbnew")
	(generator_version "10.0")
	(general
		(thickness 1.6)
		(legacy_teardrops no)
	)
	(paper "A4")
	(title_block
		(title "dpb — 14545-sa.0730WZS0815.brd")
		(comment 1 "Honey Badger (Wiwynn) / footprints 800-807 of 1066")
	)
	(layers
		(0 "F.Cu" signal "TOP")
		(4 "In1.Cu" signal "L2GND")
		(6 "In2.Cu" signal "L3")
		(8 "In3.Cu" signal "L4VCC")
		(10 "In4.Cu" signal "L5VCC")
		(12 "In5.Cu" signal "L6")
		(14 "In6.Cu" signal "L7GND")
		(2 "B.Cu" signal "BOTTOM")
		(9 "F.Adhes" user "F.Adhesive")
		(11 "B.Adhes" user "B.Adhesive")
		(13 "F.Paste" user "Package Geometry/Pastemask Top")
		(15 "B.Paste" user "Package Geometry/Pastemask Bottom")
		(5 "F.SilkS" user "Ref Des/Silkscreen Top")
		(7 "B.SilkS" user "Ref Des/Silkscreen Bottom")
		(1 "F.Mask" user "Board Geometry/Soldermask Top")
		(3 "B.Mask" user "Board Geometry/Soldermask Bottom")
		(17 "Dwgs.User" user "User.Drawings")
		(19 "Cmts.User" user "User.Comments")
		(21 "Eco1.User" user "User.Eco1")
		(23 "Eco2.User" user "User.Eco2")
		(25 "Edge.Cuts" user "Board Geometry/Outline")
		(27 "Margin" user)
		(31 "F.CrtYd" user "Package Geometry/Place Bound Top")
		(29 "B.CrtYd" user "Package Geometry/Place Bound Bottom")
		(35 "F.Fab" user "Ref Des/Assembly Top")
		(33 "B.Fab" user "Ref Des/Assembly Bottom")
	)
	(footprint ""
		(layer "F.Cu")
		(at 47.091346 -244.6274 -90)
		(property "Reference" "R497"
			(at 0 0 270)
			(layer "F.SilkS")
			(hide yes)
			(effects
				(font
					(size 1.27 1.27)
				)
			)
		)
		(property "Value" "1KR2F-3-GP"
			(at 0.064008 -3.993896 270)
			(unlocked yes)
			(layer "F.Fab")
			(hide yes)
			(effects
				(font
					(size 1.016 1.016)
					(thickness 0.1524)
				)
			)
		)
		(property "Device Type" "R402H16"
			(at 0.064008 -5.517896 270)
			(unlocked yes)
			(layer "F.Fab")
			(hide yes)
			(effects
				(font
					(size 1.016 1.016)
					(thickness 0.1524)
				)
			)
		)
		(duplicate_pad_numbers_are_jumpers no)
		(fp_line
			(start -0.508 -0.9398)
			(end -0.508 0.9398)
			(stroke
				(width 0.1524)
				(type default)
			)
			(layer "F.SilkS")
		)
		(fp_line
			(start 0.508 -0.9398)
			(end -0.508 -0.9398)
			(stroke
				(width 0.1524)
				(type default)
			)
			(layer "F.SilkS")
		)
		(fp_rect
			(start -0.508 0.9398)
			(end 0.508 -0.9398)
			(stroke
				(width 0)
				(type default)
			)
			(fill no)
			(layer "F.CrtYd")
		)
		(fp_rect
			(start -0.508 0.9398)
			(end 0.508 -0.9398)
			(stroke
				(width 0)
				(type default)
			)
			(fill no)
			(layer "F.Fab")
		)
		(pad "1" smd custom
			(at 0 -0.4445 270)
			(size 0.1397 0.1397)
			(layers "F.Cu" "F.Mask" "F.Paste")
			(net "FLT_HDD7_B")
			(options
				(clearance outline)
				(anchor circle)
			)
			(primitives
				(gr_poly
					(pts
						(arc
							(start -0.1778 -0.2794)
							(mid -0.249642 -0.249642)
							(end -0.2794 -0.1778)
						)
						(arc
							(start -0.2794 0.1778)
							(mid -0.249642 0.249642)
							(end -0.1778 0.2794)
						)
						(arc
							(start 0.1778 0.2794)
							(mid 0.249642 0.249642)
							(end 0.2794 0.1778)
						)
						(arc
							(start 0.2794 -0.1778)
							(mid 0.249642 -0.249642)
							(end 0.1778 -0.2794)
						)
					)
					(width 0)
					(fill yes)
				)
			)
		)
		(pad "2" smd custom
			(at 0 0.4445 270)
			(size 0.1397 0.1397)
			(layers "F.Cu" "F.Mask" "F.Paste")
			(net "FLT_HDD7_DRIVE")
			(options
				(clearance outline)
				(anchor circle)
			)
			(primitives
				(gr_poly
					(pts
						(arc
							(start -0.1778 -0.2794)
							(mid -0.249642 -0.249642)
							(end -0.2794 -0.1778)
						)
						(arc
							(start -0.2794 0.1778)
							(mid -0.249642 0.249642)
							(end -0.1778 0.2794)
						)
						(arc
							(start 0.1778 0.2794)
							(mid 0.249642 0.249642)
							(end 0.2794 0.1778)
						)
						(arc
							(start 0.2794 -0.1778)
							(mid 0.249642 -0.249642)
							(end 0.1778 -0.2794)
						)
					)
					(width 0)
					(fill yes)
				)
			)
		)
	)
	(footprint ""
		(layer "F.Cu")
		(at 191.897 -179.832)
		(property "Reference" "C158"
			(at 0 0 0)
			(layer "F.SilkS")
			(hide yes)
			(effects
				(font
					(size 1.27 1.27)
				)
			)
		)
		(property "Value" "SCD1U10V2KX-5GP"
			(at 1.1811 -2.7051 0)
			(unlocked yes)
			(layer "F.Fab")
			(hide yes)
			(effects
				(font
					(size 1.016 1.016)
					(thickness 0.1524)
				)
			)
		)
		(property "Device Type" "C402H22"
			(at 1.1811 -4.2291 0)
			(unlocked yes)
			(layer "F.Fab")
			(hide yes)
			(effects
				(font
					(size 1.016 1.016)
					(thickness 0.1524)
				)
			)
		)
		(duplicate_pad_numbers_are_jumpers no)
		(fp_rect
			(start -0.4318 0.9525)
			(end 0.4318 -0.9525)
			(stroke
				(width 0)
				(type default)
			)
			(fill no)
			(layer "F.CrtYd")
		)
		(fp_rect
			(start -0.4318 0.9525)
			(end 0.4318 -0.9525)
			(stroke
				(width 0)
				(type default)
			)
			(fill no)
			(layer "F.Fab")
		)
		(pad "1" smd custom
			(at 0 -0.4445)
			(size 0.1524 0.1524)
			(layers "F.Cu" "F.Mask" "F.Paste")
			(net "P3V3")
			(options
				(clearance outline)
				(anchor circle)
			)
			(primitives
				(gr_poly
					(pts
						(arc
							(start 0.3048 -0.2032)
							(mid 0.275042 -0.275042)
							(end 0.2032 -0.3048)
						)
						(arc
							(start -0.2032 -0.3048)
							(mid -0.275042 -0.275042)
							(end -0.3048 -0.2032)
						)
						(arc
							(start -0.3048 0.2032)
							(mid -0.275042 0.275042)
							(end -0.2032 0.3048)
						)
						(arc
							(start 0.2032 0.3048)
							(mid 0.275042 0.275042)
							(end 0.3048 0.2032)
						)
					)
					(width 0)
					(fill yes)
				)
			)
		)
		(pad "2" smd custom
			(at 0 0.4445)
			(size 0.1524 0.1524)
			(layers "F.Cu" "F.Mask" "F.Paste")
			(net "GND")
			(options
				(clearance outline)
				(anchor circle)
			)
			(primitives
				(gr_poly
					(pts
						(arc
							(start 0.3048 -0.2032)
							(mid 0.275042 -0.275042)
							(end 0.2032 -0.3048)
						)
						(arc
							(start -0.2032 -0.3048)
							(mid -0.275042 -0.275042)
							(end -0.3048 -0.2032)
						)
						(arc
							(start -0.3048 0.2032)
							(mid -0.275042 0.275042)
							(end -0.2032 0.3048)
						)
						(arc
							(start 0.2032 0.3048)
							(mid 0.275042 0.275042)
							(end 0.3048 0.2032)
						)
					)
					(width 0)
					(fill yes)
				)
			)
		)
	)
	(footprint ""
		(layer "F.Cu")
		(at 33.7058 -320.0146 180)
		(property "Reference" "C287"
			(at 0 0 180)
			(layer "F.SilkS")
			(hide yes)
			(effects
				(font
					(size 1.27 1.27)
				)
			)
		)
		(property "Value" "SC10U25V6KX-1GP"
			(at -0.0762 -5.1308 180)
			(unlocked yes)
			(layer "F.Fab")
			(hide yes)
			(effects
				(font
					(size 1.016 1.016)
					(thickness 0.1524)
				)
			)
		)
		(property "Device Type" "C1206H71"
			(at -0.127 -6.6548 180)
			(unlocked yes)
			(layer "F.Fab")
			(hide yes)
			(effects
				(font
					(size 1.016 1.016)
					(thickness 0.1524)
				)
			)
		)
		(duplicate_pad_numbers_are_jumpers no)
		(fp_line
			(start 1.016 2.2352)
			(end -1.016 2.2352)
			(stroke
				(width 0.1524)
				(type default)
			)
			(layer "F.SilkS")
		)
		(fp_line
			(start 1.016 0.8382)
			(end 1.016 2.2352)
			(stroke
				(width 0.1524)
				(type default)
			)
			(layer "F.SilkS")
		)
		(fp_line
			(start 1.016 -2.2352)
			(end 1.016 -0.8382)
			(stroke
				(width 0.1524)
				(type default)
			)
			(layer "F.SilkS")
		)
		(fp_line
			(start -1.016 2.2352)
			(end -1.016 0.8382)
			(stroke
				(width 0.1524)
				(type default)
			)
			(layer "F.SilkS")
		)
		(fp_line
			(start -1.016 -0.8382)
			(end -1.016 -2.2352)
			(stroke
				(width 0.1524)
				(type default)
			)
			(layer "F.SilkS")
		)
		(fp_line
			(start -1.016 -2.2352)
			(end 1.016 -2.2352)
			(stroke
				(width 0.1524)
				(type default)
			)
			(layer "F.SilkS")
		)
		(fp_rect
			(start -1.0922 2.3114)
			(end 1.0922 -2.3114)
			(stroke
				(width 0)
				(type default)
			)
			(fill no)
			(layer "F.CrtYd")
		)
		(fp_poly
			(pts
				(xy 1.0922 -2.3114) (xy 1.0922 2.3114) (xy -1.0922 2.3114) (xy -1.0922 -2.3114)
			)
			(stroke
				(width 0)
				(type default)
			)
			(fill no)
			(layer "F.Fab")
		)
		(pad "1" smd rect
			(at 0 -1.397 180)
			(size 1.651 1.27)
			(layers "F.Cu" "F.Mask" "F.Paste")
			(net "P12V_HDD11")
		)
		(pad "2" smd rect
			(at 0 1.397 180)
			(size 1.651 1.27)
			(layers "F.Cu" "F.Mask" "F.Paste")
			(net "GND")
		)
	)
	(footprint ""
		(layer "F.Cu")
		(at 55.117746 -381.5207)
		(property "Reference" "C204"
			(at 0 0 0)
			(layer "F.SilkS")
			(hide yes)
			(effects
				(font
					(size 1.27 1.27)
				)
			)
		)
		(property "Value" "SCD01U50V2KX-1GP"
			(at 1.1811 -2.7051 0)
			(unlocked yes)
			(layer "F.Fab")
			(hide yes)
			(effects
				(font
					(size 1.016 1.016)
					(thickness 0.1524)
				)
			)
		)
		(property "Device Type" "C402H22"
			(at 1.1811 -4.2291 0)
			(unlocked yes)
			(layer "F.Fab")
			(hide yes)
			(effects
				(font
					(size 1.016 1.016)
					(thickness 0.1524)
				)
			)
		)
		(duplicate_pad_numbers_are_jumpers no)
		(fp_rect
			(start -0.4318 0.9525)
			(end 0.4318 -0.9525)
			(stroke
				(width 0)
				(type default)
			)
			(fill no)
			(layer "F.CrtYd")
		)
		(fp_rect
			(start -0.4318 0.9525)
			(end 0.4318 -0.9525)
			(stroke
				(width 0)
				(type default)
			)
			(fill no)
			(layer "F.Fab")
		)
		(pad "1" smd custom
			(at 0 -0.4445)
			(size 0.1524 0.1524)
			(layers "F.Cu" "F.Mask" "F.Paste")
			(net "HDD_PRSNT_NET6")
			(options
				(clearance outline)
				(anchor circle)
			)
			(primitives
				(gr_poly
					(pts
						(arc
							(start 0.3048 -0.2032)
							(mid 0.275042 -0.275042)
							(end 0.2032 -0.3048)
						)
						(arc
							(start -0.2032 -0.3048)
							(mid -0.275042 -0.275042)
							(end -0.3048 -0.2032)
						)
						(arc
							(start -0.3048 0.2032)
							(mid -0.275042 0.275042)
							(end -0.2032 0.3048)
						)
						(arc
							(start 0.2032 0.3048)
							(mid 0.275042 0.275042)
							(end 0.3048 0.2032)
						)
					)
					(width 0)
					(fill yes)
				)
			)
		)
		(pad "2" smd custom
			(at 0 0.4445)
			(size 0.1524 0.1524)
			(layers "F.Cu" "F.Mask" "F.Paste")
			(net "GND")
			(options
				(clearance outline)
				(anchor circle)
			)
			(primitives
				(gr_poly
					(pts
						(arc
							(start 0.3048 -0.2032)
							(mid 0.275042 -0.275042)
							(end 0.2032 -0.3048)
						)
						(arc
							(start -0.2032 -0.3048)
							(mid -0.275042 -0.275042)
							(end -0.3048 -0.2032)
						)
						(arc
							(start -0.3048 0.2032)
							(mid -0.275042 0.275042)
							(end -0.2032 0.3048)
						)
						(arc
							(start 0.2032 0.3048)
							(mid 0.275042 0.275042)
							(end 0.3048 0.2032)
						)
					)
					(width 0)
					(fill yes)
				)
			)
		)
	)
	(footprint ""
		(layer "F.Cu")
		(at 252.499622 -479.996754)
		(property "Reference" "H11"
			(at 0 0 0)
			(layer "F.SilkS")
			(hide yes)
			(effects
				(font
					(size 1.27 1.27)
				)
			)
		)
		(property "Value" "HOLE315R157"
			(at -0.116332 -8.41375 0)
			(unlocked yes)
			(layer "F.Fab")
			(hide yes)
			(effects
				(font
					(size 1.016 1.016)
					(thickness 0.1524)
				)
			)
		)
		(property "Device Type" "HOLE315R157"
			(at -0.116332 -6.88975 0)
			(unlocked yes)
			(layer "F.Fab")
			(hide yes)
			(effects
				(font
					(size 1.016 1.016)
					(thickness 0.1524)
				)
			)
		)
		(duplicate_pad_numbers_are_jumpers no)
		(fp_poly
			(pts
				(arc
					(start 4.3053 0)
					(mid -4.3053 0)
					(end 4.3053 0)
				)
			)
			(stroke
				(width 0)
				(type default)
			)
			(fill no)
			(layer "F.CrtYd")
		)
		(fp_poly
			(pts
				(arc
					(start 4.3053 0)
					(mid -4.3053 0)
					(end 4.3053 0)
				)
			)
			(stroke
				(width 0)
				(type default)
			)
			(fill no)
			(layer "F.Fab")
		)
		(pad "1" thru_hole circle
			(at 0 0)
			(size 8.001 8.001)
			(drill 3.9878)
			(layers "*.Cu" "*.Mask")
			(remove_unused_layers no)
			(net "GND")
			(clearance -1.4986)
			(thermal_gap 0.3048)
			(padstack
				(mode front_inner_back)
				(layer "Inner"
					(shape circle)
					(size 4.3942 4.3942)
					(clearance 0.3048)
				)
				(layer "B.Cu"
					(shape circle)
					(size 8.001 8.001)
					(clearance -1.4986)
				)
			)
		)
	)
	(footprint ""
		(layer "F.Cu")
		(at 77.469746 -394.8557 -90)
		(property "Reference" "R192"
			(at 0 0 270)
			(layer "F.SilkS")
			(hide yes)
			(effects
				(font
					(size 1.27 1.27)
				)
			)
		)
		(property "Value" "1KR2F-3-GP"
			(at 0.064008 -3.993896 270)
			(unlocked yes)
			(layer "F.Fab")
			(hide yes)
			(effects
				(font
					(size 1.016 1.016)
					(thickness 0.1524)
				)
			)
		)
		(property "Device Type" "R402H16"
			(at 0.064008 -5.517896 270)
			(unlocked yes)
			(layer "F.Fab")
			(hide yes)
			(effects
				(font
					(size 1.016 1.016)
					(thickness 0.1524)
				)
			)
		)
		(duplicate_pad_numbers_are_jumpers no)
		(fp_line
			(start -0.508 -0.9398)
			(end -0.508 0.9398)
			(stroke
				(width 0.1524)
				(type default)
			)
			(layer "F.SilkS")
		)
		(fp_line
			(start 0.508 -0.9398)
			(end -0.508 -0.9398)
			(stroke
				(width 0.1524)
				(type default)
			)
			(layer "F.SilkS")
		)
		(fp_rect
			(start -0.508 0.9398)
			(end 0.508 -0.9398)
			(stroke
				(width 0)
				(type default)
			)
			(fill no)
			(layer "F.CrtYd")
		)
		(fp_rect
			(start -0.508 0.9398)
			(end 0.508 -0.9398)
			(stroke
				(width 0)
				(type default)
			)
			(fill no)
			(layer "F.Fab")
		)
		(pad "1" smd custom
			(at 0 -0.4445 270)
			(size 0.1397 0.1397)
			(layers "F.Cu" "F.Mask" "F.Paste")
			(net "P3V3")
			(options
				(clearance outline)
				(anchor circle)
			)
			(primitives
				(gr_poly
					(pts
						(arc
							(start -0.1778 -0.2794)
							(mid -0.249642 -0.249642)
							(end -0.2794 -0.1778)
						)
						(arc
							(start -0.2794 0.1778)
							(mid -0.249642 0.249642)
							(end -0.1778 0.2794)
						)
						(arc
							(start 0.1778 0.2794)
							(mid 0.249642 0.249642)
							(end 0.2794 0.1778)
						)
						(arc
							(start 0.2794 -0.1778)
							(mid 0.249642 -0.249642)
							(end 0.1778 -0.2794)
						)
					)
					(width 0)
					(fill yes)
				)
			)
		)
		(pad "2" smd custom
			(at 0 0.4445 270)
			(size 0.1397 0.1397)
			(layers "F.Cu" "F.Mask" "F.Paste")
			(net "SW_PWR_HDD6")
			(options
				(clearance outline)
				(anchor circle)
			)
			(primitives
				(gr_poly
					(pts
						(arc
							(start -0.1778 -0.2794)
							(mid -0.249642 -0.249642)
							(end -0.2794 -0.1778)
						)
						(arc
							(start -0.2794 0.1778)
							(mid -0.249642 0.249642)
							(end -0.1778 0.2794)
						)
						(arc
							(start 0.1778 0.2794)
							(mid 0.249642 0.249642)
							(end 0.2794 0.1778)
						)
						(arc
							(start 0.2794 -0.1778)
							(mid 0.249642 -0.249642)
							(end 0.1778 -0.2794)
						)
					)
					(width 0)
					(fill yes)
				)
			)
		)
	)
	(footprint ""
		(layer "F.Cu")
		(at 42.468546 -131.7879 180)
		(property "Reference" "R316"
			(at 0 0 180)
			(layer "F.SilkS")
			(hide yes)
			(effects
				(font
					(size 1.27 1.27)
				)
			)
		)
		(property "Value" "4K7R2J-2-GP"
			(at 0.064008 -3.993896 180)
			(unlocked yes)
			(layer "F.Fab")
			(hide yes)
			(effects
				(font
					(size 1.016 1.016)
					(thickness 0.1524)
				)
			)
		)
		(property "Device Type" "R402H16"
			(at 0.064008 -5.517896 180)
			(unlocked yes)
			(layer "F.Fab")
			(hide yes)
			(effects
				(font
					(size 1.016 1.016)
					(thickness 0.1524)
				)
			)
		)
		(duplicate_pad_numbers_are_jumpers no)
		(fp_line
			(start 0.508 -0.9398)
			(end -0.508 -0.9398)
			(stroke
				(width 0.1524)
				(type default)
			)
			(layer "F.SilkS")
		)
		(fp_line
			(start -0.508 -0.9398)
			(end -0.508 0.9398)
			(stroke
				(width 0.1524)
				(type default)
			)
			(layer "F.SilkS")
		)
		(fp_rect
			(start -0.508 0.9398)
			(end 0.508 -0.9398)
			(stroke
				(width 0)
				(type default)
			)
			(fill no)
			(layer "F.CrtYd")
		)
		(fp_rect
			(start -0.508 0.9398)
			(end 0.508 -0.9398)
			(stroke
				(width 0)
				(type default)
			)
			(fill no)
			(layer "F.Fab")
		)
		(pad "1" smd custom
			(at 0 -0.4445 180)
			(size 0.1397 0.1397)
			(layers "F.Cu" "F.Mask" "F.Paste")
			(net "P3V3")
			(options
				(clearance outline)
				(anchor circle)
			)
			(primitives
				(gr_poly
					(pts
						(arc
							(start -0.1778 -0.2794)
							(mid -0.249642 -0.249642)
							(end -0.2794 -0.1778)
						)
						(arc
							(start -0.2794 0.1778)
							(mid -0.249642 0.249642)
							(end -0.1778 0.2794)
						)
						(arc
							(start 0.1778 0.2794)
							(mid 0.249642 0.249642)
							(end 0.2794 0.1778)
						)
						(arc
							(start 0.2794 -0.1778)
							(mid 0.249642 -0.249642)
							(end 0.1778 -0.2794)
						)
					)
					(width 0)
					(fill yes)
				)
			)
		)
		(pad "2" smd custom
			(at 0 0.4445 180)
			(size 0.1397 0.1397)
			(layers "F.Cu" "F.Mask" "F.Paste")
			(net "I2C_B_TMP2_A1")
			(options
				(clearance outline)
				(anchor circle)
			)
			(primitives
				(gr_poly
					(pts
						(arc
							(start -0.1778 -0.2794)
							(mid -0.249642 -0.249642)
							(end -0.2794 -0.1778)
						)
						(arc
							(start -0.2794 0.1778)
							(mid -0.249642 0.249642)
							(end -0.1778 0.2794)
						)
						(arc
							(start 0.1778 0.2794)
							(mid 0.249642 0.249642)
							(end 0.2794 0.1778)
						)
						(arc
							(start 0.2794 -0.1778)
							(mid 0.249642 -0.249642)
							(end 0.1778 -0.2794)
						)
					)
					(width 0)
					(fill yes)
				)
			)
		)
	)
	(footprint ""
		(layer "F.Cu")
		(at 70.231 -81.153)
		(property "Reference" "TP34"
			(at 0 0 0)
			(layer "F.SilkS")
			(hide yes)
			(effects
				(font
					(size 1.27 1.27)
				)
			)
		)
		(property "Value" "TPAD32-GP"
			(at 0 -3.166364 0)
			(unlocked yes)
			(layer "F.Fab")
			(hide yes)
			(effects
				(font
					(size 1.016 1.016)
					(thickness 0.1524)
				)
			)
		)
		(property "Device Type" "TPAD32"
			(at 0 -4.690618 0)
			(unlocked yes)
			(layer "F.Fab")
			(hide yes)
			(effects
				(font
					(size 1.016 1.016)
					(thickness 0.1524)
				)
			)
		)
		(duplicate_pad_numbers_are_jumpers no)
		(fp_poly
			(pts
				(arc
					(start 0.4064 0)
					(mid -0.4064 0)
					(end 0.4064 0)
				)
			)
			(stroke
				(width 0)
				(type default)
			)
			(fill no)
			(layer "F.CrtYd")
		)
		(fp_poly
			(pts
				(arc
					(start 0.7112 0)
					(mid -0.7112 0)
					(end 0.7112 0)
				)
			)
			(stroke
				(width 0)
				(type default)
			)
			(fill no)
			(layer "F.Fab")
		)
		(pad "1" smd circle
			(at 0 0)
			(size 0.8128 0.8128)
			(layers "F.Cu" "F.Mask" "F.Paste")
			(net "ACT_HDD9")
		)
	)
)
